# BASEBOARD_FAB2 (Tioga Pass) — schematic netlist excerpt (pin names and nets, part order shuffled) for the footprints in the layout excerpt that follows; sources: Cadence DE-HDL packaged netlist, KiCad conversion of Wiwynn_Tioga_Pass_MB.brd

R1U19  RES  20.0 1% CHIP  pkg 0402  page 159 : A = SMB_SMLINK0_STBY_LVC3_SCL ; B = SMB_SPRINGVILLE_STBY_LVC3_SCL
C3M19  CAP_A  1.0UF 6.3V 10% X6S  pkg 0402V  page 127 : A = P1V05_PCH_STBY_VCCA_PLL1 ; B = GND
SH3P2  SHUNT  EMPTY  pkg SH0201  page 212 : A = VSENSE_PVCCIO_CPU0_SKT_VRTN ; B = VSENSE_PVCCIO_CPU0_AVSN

(kicad_pcb
	(version 20260206)
	(generator "pcbnew")
	(generator_version "10.0")
	(general
		(thickness 1.6)
		(legacy_teardrops no)
	)
	(paper "A4")
	(title_block
		(title "Wiwynn_Tioga_Pass_MB.brd")
		(comment 1 "Tioga Pass / footprints 4025-4027 of 4770")
	)
	(layers
		(0 "F.Cu" signal "TOP")
		(4 "In1.Cu" signal "L2GND")
		(6 "In2.Cu" signal "L3")
		(8 "In3.Cu" signal "L4GND")
		(10 "In4.Cu" signal "L5")
		(12 "In5.Cu" signal "L6GND")
		(14 "In6.Cu" signal "L7VCC")
		(16 "In7.Cu" signal "L8VCC")
		(18 "In8.Cu" signal "L9GND")
		(20 "In9.Cu" signal "L10")
		(22 "In10.Cu" signal "L11GND")
		(24 "In11.Cu" signal "L12")
		(26 "In12.Cu" signal "L13GND")
		(2 "B.Cu" signal "BOTTOM")
		(9 "F.Adhes" user "F.Adhesive")
		(11 "B.Adhes" user "B.Adhesive")
		(13 "F.Paste" user "Package Geometry/Pastemask Top")
		(15 "B.Paste" user "Package Geometry/Pastemask Bottom")
		(5 "F.SilkS" user "Ref Des/Silkscreen Top")
		(7 "B.SilkS" user "Ref Des/Silkscreen Bottom")
		(1 "F.Mask" user "Board Geometry/Soldermask Top")
		(3 "B.Mask" user "Board Geometry/Soldermask Bottom")
		(17 "Dwgs.User" user "User.Drawings")
		(19 "Cmts.User" user "User.Comments")
		(21 "Eco1.User" user "User.Eco1")
		(23 "Eco2.User" user "User.Eco2")
		(25 "Edge.Cuts" user "Board Geometry/Outline")
		(27 "Margin" user)
		(31 "F.CrtYd" user "Package Geometry/Place Bound Top")
		(29 "B.CrtYd" user "Package Geometry/Place Bound Bottom")
		(35 "F.Fab" user "Ref Des/Assembly Top")
		(33 "B.Fab" user "Ref Des/Assembly Bottom")
	)
	(footprint ""
		(layer "B.Cu")
		(at 379.6792 -137.2108)
		(property "Reference" "C3M19"
			(at 0 0 0)
			(layer "B.SilkS")
			(hide yes)
			(effects
				(font
					(size 1.27 1.27)
				)
				(justify mirror)
			)
		)
		(property "Value" ""
			(at 0 0 0)
			(layer "B.Fab")
			(effects
				(font
					(size 1.27 1.27)
				)
				(justify mirror)
			)
		)
		(duplicate_pad_numbers_are_jumpers no)
		(fp_poly
			(pts
				(xy -0.3048 -0.1016) (xy -0.3048 0.9906) (xy 0.3048 0.9906) (xy 0.3048 -0.1016)
			)
			(stroke
				(width 0)
				(type default)
			)
			(fill no)
			(layer "B.CrtYd")
		)
		(fp_line
			(start -0.3048 -0.1016)
			(end 0.3048 -0.1016)
			(stroke
				(width 0.1)
				(type default)
			)
			(layer "B.Fab")
		)
		(fp_line
			(start -0.3048 0.9906)
			(end -0.3048 -0.1016)
			(stroke
				(width 0.1)
				(type default)
			)
			(layer "B.Fab")
		)
		(fp_line
			(start 0.3048 -0.1016)
			(end 0.3048 0.9906)
			(stroke
				(width 0.1)
				(type default)
			)
			(layer "B.Fab")
		)
		(fp_line
			(start 0.3048 0.9906)
			(end -0.3048 0.9906)
			(stroke
				(width 0.1)
				(type default)
			)
			(layer "B.Fab")
		)
		(pad "1" smd rect
			(at 0 0 180)
			(size 0.508 0.508)
			(layers "B.Cu" "B.Mask" "B.Paste")
			(net "P1V05_PCH_STBY_VCCA_PLL1")
		)
		(pad "2" smd rect
			(at 0 0.889 180)
			(size 0.508 0.508)
			(layers "B.Cu" "B.Mask" "B.Paste")
			(net "GND")
		)
		(zone
			(layer "B.Cu")
			(hatch none 0.5)
			(connect_pads
				(clearance 0)
			)
			(min_thickness 0.25)
			(keepout
				(tracks allowed)
				(vias not_allowed)
				(pads allowed)
				(copperpour not_allowed)
				(footprints allowed)
			)
			(placement
				(enabled no)
				(sheetname "")
			)
			(fill
				(thermal_gap 0.5)
				(thermal_bridge_width 0.5)
				(island_removal_mode 0)
			)
			(polygon
				(pts
					(xy 379.9332 -136.9568) (xy 379.4252 -136.9568) (xy 379.4252 -136.5758) (xy 379.9332 -136.5758)
				)
			)
		)
		(zone
			(layer "B.Cu")
			(hatch none 0.5)
			(connect_pads
				(clearance 0)
			)
			(min_thickness 0.25)
			(keepout
				(tracks not_allowed)
				(vias allowed)
				(pads allowed)
				(copperpour not_allowed)
				(footprints allowed)
			)
			(placement
				(enabled no)
				(sheetname "")
			)
			(fill
				(thermal_gap 0.5)
				(thermal_bridge_width 0.5)
				(island_removal_mode 0)
			)
			(polygon
				(pts
					(xy 379.9332 -136.5758) (xy 379.4252 -136.5758) (xy 379.4252 -136.9568) (xy 379.9332 -136.9568)
				)
			)
		)
	)
	(footprint ""
		(layer "B.Cu")
		(at 354.460048 -86.93404 180)
		(property "Reference" "SH3P2"
			(at 0 0 0)
			(layer "B.SilkS")
			(hide yes)
			(effects
				(font
					(size 1.27 1.27)
				)
				(justify mirror)
			)
		)
		(property "Value" ""
			(at 0 0 0)
			(layer "B.Fab")
			(effects
				(font
					(size 1.27 1.27)
				)
				(justify mirror)
			)
		)
		(duplicate_pad_numbers_are_jumpers no)
		(fp_poly
			(pts
				(xy 0.1651 -0.0508) (xy 0.1651 0.5842) (xy -0.1651 0.5842) (xy -0.1651 -0.0508)
			)
			(stroke
				(width 0)
				(type default)
			)
			(fill no)
			(layer "B.CrtYd")
		)
		(fp_line
			(start 0.1651 0.5842)
			(end 0.1651 -0.0508)
			(stroke
				(width 0.1)
				(type default)
			)
			(layer "B.Fab")
		)
		(fp_line
			(start 0.1651 -0.0508)
			(end -0.1651 -0.0508)
			(stroke
				(width 0.1)
				(type default)
			)
			(layer "B.Fab")
		)
		(fp_line
			(start -0.1651 0.5842)
			(end 0.1651 0.5842)
			(stroke
				(width 0.1)
				(type default)
			)
			(layer "B.Fab")
		)
		(fp_line
			(start -0.1651 -0.0508)
			(end -0.1651 0.5842)
			(stroke
				(width 0.1)
				(type default)
			)
			(layer "B.Fab")
		)
		(pad "1" smd custom
			(at 0 0 180)
			(size 0.0762 0.0762)
			(layers "B.Cu" "B.Mask" "B.Paste")
			(net "VSENSE_PVCCIO_CPU0_SKT_VRTN")
			(options
				(clearance outline)
				(anchor circle)
			)
			(primitives
				(gr_poly
					(pts
						(arc
							(start -0.1524 0.10795)
							(mid -0.098518 0.130268)
							(end -0.0762 0.18415)
						)
						(xy -0.0762 0.22225) (xy 0.0762 0.22225)
						(arc
							(start 0.0762 0.18415)
							(mid 0.098518 0.130268)
							(end 0.1524 0.10795)
						)
						(xy 0.1524 -0.22225) (xy -0.1524 -0.22225)
					)
					(width 0)
					(fill yes)
				)
			)
		)
		(pad "2" smd custom
			(at 0 0.5334)
			(size 0.0762 0.0762)
			(layers "B.Cu" "B.Mask" "B.Paste")
			(net "VSENSE_PVCCIO_CPU0_AVSN")
			(options
				(clearance outline)
				(anchor circle)
			)
			(primitives
				(gr_poly
					(pts
						(arc
							(start -0.1524 0.10795)
							(mid -0.098518 0.130268)
							(end -0.0762 0.18415)
						)
						(xy -0.0762 0.22225) (xy 0.0762 0.22225)
						(arc
							(start 0.0762 0.18415)
							(mid 0.098518 0.130268)
							(end 0.1524 0.10795)
						)
						(xy 0.1524 -0.22225) (xy -0.1524 -0.22225)
					)
					(width 0)
					(fill yes)
				)
			)
		)
	)
	(footprint ""
		(layer "B.Cu")
		(at 485.8512 -128.2065 180)
		(property "Reference" "R1U19"
			(at 0 0 0)
			(layer "B.SilkS")
			(hide yes)
			(effects
				(font
					(size 1.27 1.27)
				)
				(justify mirror)
			)
		)
		(property "Value" ""
			(at 0 0 0)
			(layer "B.Fab")
			(effects
				(font
					(size 1.27 1.27)
				)
				(justify mirror)
			)
		)
		(duplicate_pad_numbers_are_jumpers no)
		(fp_poly
			(pts
				(xy 0.2794 -0.1016) (xy -0.2794 -0.1016) (xy -0.2794 0.9906) (xy 0.2794 0.9906)
			)
			(stroke
				(width 0)
				(type default)
			)
			(fill no)
			(layer "B.CrtYd")
		)
		(fp_line
			(start 0.2794 0.9906)
			(end -0.2794 0.9906)
			(stroke
				(width 0.1)
				(type default)
			)
			(layer "B.Fab")
		)
		(fp_line
			(start 0.2794 -0.1016)
			(end 0.2794 0.9906)
			(stroke
				(width 0.1)
				(type default)
			)
			(layer "B.Fab")
		)
		(fp_line
			(start -0.2794 0.9906)
			(end -0.2794 -0.1016)
			(stroke
				(width 0.1)
				(type default)
			)
			(layer "B.Fab")
		)
		(fp_line
			(start -0.2794 -0.1016)
			(end 0.2794 -0.1016)
			(stroke
				(width 0.1)
				(type default)
			)
			(layer "B.Fab")
		)
		(pad "1" smd rect
			(at 0 0)
			(size 0.508 0.508)
			(layers "B.Cu" "B.Mask" "B.Paste")
			(net "SMB_SMLINK0_STBY_LVC3_SCL")
		)
		(pad "2" smd rect
			(at 0 0.889)
			(size 0.508 0.508)
			(layers "B.Cu" "B.Mask" "B.Paste")
			(net "SMB_SPRINGVILLE_STBY_LVC3_SCL")
		)
		(zone
			(layer "B.Cu")
			(hatch none 0.5)
			(connect_pads
				(clearance 0)
			)
			(min_thickness 0.25)
			(keepout
				(tracks not_allowed)
				(vias allowed)
				(pads allowed)
				(copperpour not_allowed)
				(footprints allowed)
			)
			(placement
				(enabled no)
				(sheetname "")
			)
			(fill
				(thermal_gap 0.5)
				(thermal_bridge_width 0.5)
				(island_removal_mode 0)
			)
			(polygon
				(pts
					(xy 485.5972 -128.8415) (xy 486.1052 -128.8415) (xy 486.1052 -128.4605) (xy 485.5972 -128.4605)
				)
			)
		)
		(zone
			(layer "B.Cu")
			(hatch none 0.5)
			(connect_pads
				(clearance 0)
			)
			(min_thickness 0.25)
			(keepout
				(tracks allowed)
				(vias not_allowed)
				(pads allowed)
				(copperpour not_allowed)
				(footprints allowed)
			)
			(placement
				(enabled no)
				(sheetname "")
			)
			(fill
				(thermal_gap 0.5)
				(thermal_bridge_width 0.5)
				(island_removal_mode 0)
			)
			(polygon
				(pts
					(xy 485.5972 -128.4605) (xy 486.1052 -128.4605) (xy 486.1052 -128.8415) (xy 485.5972 -128.8415)
				)
			)
		)
	)
)
